(kicad_pcb
	(version 20241229)
	(generator "pcbnew")
	(generator_version "9.0")
	(general
		(thickness 1.552)
		(legacy_teardrops no)
	)
	(paper "A4")
	(title_block
		(date "2023-07-25")
		(rev "1.1.4")
		(comment 9 "footprints 178-181 of 379")
	)
	(layers
		(0 "F.Cu" signal)
		(4 "In1.Cu" signal)
		(6 "In2.Cu" signal)
		(8 "In3.Cu" signal)
		(10 "In4.Cu" signal)
		(12 "In5.Cu" signal)
		(14 "In6.Cu" signal)
		(2 "B.Cu" signal)
		(9 "F.Adhes" user "F.Adhesive")
		(11 "B.Adhes" user "B.Adhesive")
		(13 "F.Paste" user)
		(15 "B.Paste" user)
		(5 "F.SilkS" user "F.Silkscreen")
		(7 "B.SilkS" user "B.Silkscreen")
		(1 "F.Mask" user)
		(3 "B.Mask" user)
		(17 "Dwgs.User" user "User.Drawings")
		(19 "Cmts.User" user "User.Comments")
		(21 "Eco1.User" user "User.Eco1")
		(23 "Eco2.User" user "User.Eco2")
		(25 "Edge.Cuts" user)
		(27 "Margin" user)
		(31 "F.CrtYd" user "F.Courtyard")
		(29 "B.CrtYd" user "B.Courtyard")
		(35 "F.Fab" user)
		(33 "B.Fab" user)
	)
	(footprint "antmicro-footprints:SW_DIP_SPSTx02_Slide_Copal_CVS-02xB_W5.9mm_P1mm"
		(layer "F.Cu")
		(at 158.75 121.15 90)
		(descr "SMD 2x-dip-switch SPST Copal_CVS-02xB, Slide, row spacing 5.9 mm")
		(tags "SMD DIP Switch SPST Slide 5.9mm")
		(property "Reference" "SW1"
			(at 0 -2.08 90)
			(layer "F.SilkS")
			(effects
				(font
					(size 0.65 0.65)
					(thickness 0.15)
				)
				(justify left bottom)
			)
		)
		(property "Value" "SW_CVS-02B"
			(at 0 2.91 90)
			(layer "F.Fab")
			(hide yes)
			(effects
				(font
					(size 0.7 0.7)
					(thickness 0.15)
				)
				(justify left bottom)
			)
		)
		(property "Datasheet" "https://www.mouser.com/datasheet/2/972/cvs-1827291.pdf"
			(at 0 0 90)
			(layer "F.Fab")
			(hide yes)
			(effects
				(font
					(size 1.27 1.27)
					(thickness 0.15)
				)
			)
		)
		(property "Description" "Slide switch, 2-position SMD Slide switch, 2-channel"
			(at 0 0 90)
			(layer "F.Fab")
			(hide yes)
			(effects
				(font
					(size 1.27 1.27)
					(thickness 0.15)
				)
			)
		)
		(property "Author" "Antmicro"
			(at 279.9 -37.6 0)
			(layer "F.Fab")
			(hide yes)
			(effects
				(font
					(size 1 1)
					(thickness 0.15)
				)
			)
		)
		(property "License" "Apache-2.0"
			(at 279.9 -37.6 0)
			(layer "F.Fab")
			(hide yes)
			(effects
				(font
					(size 1 1)
					(thickness 0.15)
				)
			)
		)
		(property "MPN" "CVS-02B"
			(at 279.9 -37.6 0)
			(layer "F.Fab")
			(hide yes)
			(effects
				(font
					(size 1 1)
					(thickness 0.15)
				)
			)
		)
		(property "Manufacturer" "Nidec Components"
			(at 279.9 -37.6 0)
			(layer "F.Fab")
			(hide yes)
			(effects
				(font
					(size 1 1)
					(thickness 0.15)
				)
			)
		)
		(property ki_fp_filters "SW?DIP?x2*")
		(sheetname "/Peripherals/")
		(sheetfile "peripherals.kicad_sch")
		(attr smd)
		(fp_line
			(start -1.561 -1.911)
			(end 1.56 -1.911)
			(stroke
				(width 0.15)
				(type solid)
			)
			(layer "F.SilkS")
		)
		(fp_line
			(start -1.561 1.908)
			(end 1.56 1.908)
			(stroke
				(width 0.15)
				(type solid)
			)
			(layer "F.SilkS")
		)
		(fp_circle
			(center -3.4 -1.1)
			(end -3.35 -1.06)
			(stroke
				(width 0.15)
				(type solid)
			)
			(fill yes)
			(layer "F.SilkS")
		)
		(fp_rect
			(start -3.6 -2)
			(end 3.6 2)
			(stroke
				(width 0.05)
				(type solid)
			)
			(fill no)
			(layer "F.CrtYd")
		)
		(fp_line
			(start 0.998 -0.75)
			(end -1 -0.75)
			(stroke
				(width 0.15)
				(type solid)
			)
			(layer "F.Fab")
		)
		(fp_line
			(start -0.335 -0.75)
			(end -0.335 -0.25)
			(stroke
				(width 0.15)
				(type solid)
			)
			(layer "F.Fab")
		)
		(fp_line
			(start -1 -0.75)
			(end -1 -0.25)
			(stroke
				(width 0.15)
				(type solid)
			)
			(layer "F.Fab")
		)
		(fp_line
			(start -1 -0.652)
			(end -0.335 -0.652)
			(stroke
				(width 0.15)
				(type solid)
			)
			(layer "F.Fab")
		)
		(fp_line
			(start -1 -0.552)
			(end -0.335 -0.552)
			(stroke
				(width 0.15)
				(type solid)
			)
			(layer "F.Fab")
		)
		(fp_line
			(start -2.351 -0.5)
			(end -1.351 -1.5)
			(stroke
				(width 0.15)
				(type solid)
			)
			(layer "F.Fab")
		)
		(fp_line
			(start -1 -0.452)
			(end -0.335 -0.452)
			(stroke
				(width 0.15)
				(type solid)
			)
			(layer "F.Fab")
		)
		(fp_line
			(start -1 -0.351)
			(end -0.335 -0.351)
			(stroke
				(width 0.15)
				(type solid)
			)
			(layer "F.Fab")
		)
		(fp_line
			(start 0.998 -0.25)
			(end 0.998 -0.75)
			(stroke
				(width 0.15)
				(type solid)
			)
			(layer "F.Fab")
		)
		(fp_line
			(start -1 -0.25)
			(end 0.998 -0.25)
			(stroke
				(width 0.15)
				(type solid)
			)
			(layer "F.Fab")
		)
		(fp_line
			(start 0.998 0.248)
			(end -1 0.248)
			(stroke
				(width 0.15)
				(type solid)
			)
			(layer "F.Fab")
		)
		(fp_line
			(start -0.335 0.248)
			(end -0.335 0.748)
			(stroke
				(width 0.15)
				(type solid)
			)
			(layer "F.Fab")
		)
		(fp_line
			(start -1 0.248)
			(end -1 0.748)
			(stroke
				(width 0.15)
				(type solid)
			)
			(layer "F.Fab")
		)
		(fp_line
			(start -1 0.349)
			(end -0.335 0.349)
			(stroke
				(width 0.15)
				(type solid)
			)
			(layer "F.Fab")
		)
		(fp_line
			(start -1 0.45)
			(end -0.335 0.45)
			(stroke
				(width 0.15)
				(type solid)
			)
			(layer "F.Fab")
		)
		(fp_line
			(start -1 0.55)
			(end -0.335 0.55)
			(stroke
				(width 0.15)
				(type solid)
			)
			(layer "F.Fab")
		)
		(fp_line
			(start -1 0.65)
			(end -0.335 0.65)
			(stroke
				(width 0.15)
				(type solid)
			)
			(layer "F.Fab")
		)
		(fp_line
			(start 0.998 0.748)
			(end 0.998 0.248)
			(stroke
				(width 0.15)
				(type solid)
			)
			(layer "F.Fab")
		)
		(fp_line
			(start -1 0.748)
			(end 0.998 0.748)
			(stroke
				(width 0.15)
				(type solid)
			)
			(layer "F.Fab")
		)
		(fp_rect
			(start 2.35 1.499)
			(end -2.351 -1.5)
			(stroke
				(width 0.15)
				(type solid)
			)
			(fill no)
			(layer "F.Fab")
		)
		(fp_text user "License: Apache-2.0"
			(at -3.6 6.908 90)
			(layer "F.Fab")
			(effects
				(font
					(size 0.7 0.7)
					(thickness 0.15)
				)
				(justify left bottom)
			)
		)
		(fp_text user "${REFERENCE}"
			(at -3.6 4.91 90)
			(layer "F.Fab")
			(effects
				(font
					(size 0.7 0.7)
					(thickness 0.15)
				)
				(justify left bottom)
			)
		)
		(fp_text user "on"
			(at -1.5 0.739 0)
			(layer "F.Fab")
			(effects
				(font
					(size 0.7 0.7)
					(thickness 0.15)
				)
				(justify right bottom)
			)
		)
		(fp_text user "Author: Antmicro"
			(at -3.6 5.908 90)
			(layer "F.Fab")
			(effects
				(font
					(size 0.7 0.7)
					(thickness 0.15)
				)
				(justify left bottom)
			)
		)
		(pad "1" smd rect
			(at -2.95 -0.5 90)
			(size 1.2 0.5)
			(layers "F.Cu" "F.Mask" "F.Paste")
			(net 1 "GND")
			(pintype "passive")
		)
		(pad "2" smd rect
			(at -2.95 0.5 90)
			(size 1.2 0.5)
			(layers "F.Cu" "F.Mask" "F.Paste")
			(net 1 "GND")
			(pintype "passive")
		)
		(pad "3" smd rect
			(at 2.95 0.5 90)
			(size 1.2 0.5)
			(layers "F.Cu" "F.Mask" "F.Paste")
			(net 44 "DIP0")
			(pintype "passive")
		)
		(pad "4" smd rect
			(at 2.95 -0.5 90)
			(size 1.2 0.5)
			(layers "F.Cu" "F.Mask" "F.Paste")
			(net 43 "DIP1")
			(pintype "passive")
		)
		(pad "SH" smd rect
			(at -2.15 -1.5 90)
			(size 0.7 0.7)
			(layers "F.Cu" "F.Mask" "F.Paste")
			(net 1 "GND")
			(pinfunction "SH")
			(pintype "power_in")
		)
		(pad "SH" smd rect
			(at -2.15 1.5 90)
			(size 0.7 0.7)
			(layers "F.Cu" "F.Mask" "F.Paste")
			(net 1 "GND")
			(pinfunction "SH")
			(pintype "power_in")
		)
		(pad "SH" smd rect
			(at 2.15 -1.5 90)
			(size 0.7 0.7)
			(layers "F.Cu" "F.Mask" "F.Paste")
			(net 1 "GND")
			(pinfunction "SH")
			(pintype "power_in")
		)
		(pad "SH" smd rect
			(at 2.15 1.5 90)
			(size 0.7 0.7)
			(layers "F.Cu" "F.Mask" "F.Paste")
			(net 1 "GND")
			(pinfunction "SH")
			(pintype "power_in")
		)
	)
	(footprint "antmicro-footprints:R_0402_1005Metric"
		(layer "F.Cu")
		(at 140.57 113.6 -90)
		(descr "Resistor SMD 0402")
		(tags "resistor SMD 0402")
		(property "Reference" "R34"
			(at 0.96 0.36 270)
			(layer "F.SilkS")
			(effects
				(font
					(size 0.65 0.65)
					(thickness 0.15)
				)
				(justify left bottom)
			)
		)
		(property "Value" "R_24k_0402"
			(at 0 1.4 270)
			(layer "F.Fab")
			(hide yes)
			(effects
				(font
					(size 0.7 0.7)
					(thickness 0.15)
				)
				(justify left bottom)
			)
		)
		(property "Datasheet" "https://www.bourns.com/docs/product-datasheets/cr.pdf"
			(at 0 0 270)
			(layer "F.Fab")
			(hide yes)
			(effects
				(font
					(size 1.27 1.27)
					(thickness 0.15)
				)
			)
		)
		(property "Description" "SMD Chip Resistor, 24 kohm, ± 1%, 100 mW, 0402 [1005 Metric], Thick Film, Precision"
			(at 0 0 270)
			(layer "F.Fab")
			(hide yes)
			(effects
				(font
					(size 1.27 1.27)
					(thickness 0.15)
				)
			)
		)
		(property "Author" "Antmicro"
			(at 26.79 253.99 0)
			(layer "F.Fab")
			(hide yes)
			(effects
				(font
					(size 1 1)
					(thickness 0.15)
				)
			)
		)
		(property "License" "Apache-2.0"
			(at 26.79 253.99 0)
			(layer "F.Fab")
			(hide yes)
			(effects
				(font
					(size 1 1)
					(thickness 0.15)
				)
			)
		)
		(property "MPN" "CR0402-FX-2402GLF"
			(at 26.79 253.99 0)
			(layer "F.Fab")
			(hide yes)
			(effects
				(font
					(size 1 1)
					(thickness 0.15)
				)
			)
		)
		(property "Manufacturer" "Bourns"
			(at 26.79 253.99 0)
			(layer "F.Fab")
			(hide yes)
			(effects
				(font
					(size 1 1)
					(thickness 0.15)
				)
			)
		)
		(property "Tolerance" "1%"
			(at 26.79 253.99 0)
			(layer "F.Fab")
			(hide yes)
			(effects
				(font
					(size 1 1)
					(thickness 0.15)
				)
			)
		)
		(property "Val" "24k"
			(at 26.79 253.99 0)
			(layer "F.Fab")
			(hide yes)
			(effects
				(font
					(size 1 1)
					(thickness 0.15)
				)
			)
		)
		(sheetname "/Power Supply/")
		(sheetfile "supply.kicad_sch")
		(attr smd)
		(fp_rect
			(start -0.925 -0.47)
			(end 0.925 0.47)
			(stroke
				(width 0.05)
				(type default)
			)
			(fill no)
			(layer "F.CrtYd")
		)
		(fp_rect
			(start -0.5 -0.25)
			(end 0.5 0.25)
			(stroke
				(width 0.15)
				(type solid)
			)
			(fill no)
			(layer "F.Fab")
		)
		(fp_text user "${REFERENCE}"
			(at -0.95 3.168 270)
			(layer "F.Fab")
			(effects
				(font
					(size 0.7 0.7)
					(thickness 0.15)
				)
				(justify left bottom)
			)
		)
		(fp_text user "Author: Antmicro"
			(at -0.95 4.169 270)
			(layer "F.Fab")
			(effects
				(font
					(size 0.7 0.7)
					(thickness 0.15)
				)
				(justify left bottom)
			)
		)
		(fp_text user "License: Apache-2.0"
			(at -0.95 5.169 270)
			(layer "F.Fab")
			(effects
				(font
					(size 0.7 0.7)
					(thickness 0.15)
				)
				(justify left bottom)
			)
		)
		(pad "1" smd roundrect
			(at -0.48 0 270)
			(size 0.59 0.64)
			(layers "F.Cu" "F.Mask" "F.Paste")
			(roundrect_rratio 0.25)
			(net 1 "GND")
			(pintype "passive")
		)
		(pad "2" smd roundrect
			(at 0.48 0 270)
			(size 0.59 0.64)
			(layers "F.Cu" "F.Mask" "F.Paste")
			(roundrect_rratio 0.25)
			(net 282 "Net-(U9-ADJ)")
			(pintype "passive")
		)
	)
	(footprint "antmicro-footprints:C_0603_1608Metric"
		(layer "F.Cu")
		(at 146.24 106.5 180)
		(descr "Capacitor SMD 0603")
		(tags "capacitor 0603")
		(property "Reference" "C17"
			(at 1.01 0.96 180)
			(layer "F.SilkS")
			(effects
				(font
					(size 0.65 0.65)
					(thickness 0.15)
				)
				(justify left bottom)
			)
		)
		(property "Value" "C_1u_0603"
			(at 0 1.6 180)
			(layer "F.Fab")
			(hide yes)
			(effects
				(font
					(size 0.7 0.7)
					(thickness 0.15)
				)
				(justify left bottom)
			)
		)
		(property "Datasheet" "https://spicat.kyocera-avx.com/product/mlcc/chartview/0603YD105KAT2A/"
			(at 0 0 180)
			(layer "F.Fab")
			(hide yes)
			(effects
				(font
					(size 1.27 1.27)
					(thickness 0.15)
				)
			)
		)
		(property "Description" "SMD Multilayer Ceramic Capacitor, 1 µF, 16 V, 0603 [1608 Metric], ± 10%, X5R, AVX 0603 MLCC"
			(at 0 0 180)
			(layer "F.Fab")
			(hide yes)
			(effects
				(font
					(size 1.27 1.27)
					(thickness 0.15)
				)
			)
		)
		(property "Author" "Antmicro"
			(at 292.48 213 0)
			(layer "F.Fab")
			(hide yes)
			(effects
				(font
					(size 1 1)
					(thickness 0.15)
				)
			)
		)
		(property "Dielectric" ""
			(at 292.48 213 0)
			(layer "F.Fab")
			(hide yes)
			(effects
				(font
					(size 1 1)
					(thickness 0.15)
				)
			)
		)
		(property "License" "Apache-2.0"
			(at 292.48 213 0)
			(layer "F.Fab")
			(hide yes)
			(effects
				(font
					(size 1 1)
					(thickness 0.15)
				)
			)
		)
		(property "MPN" "0603YD105KAT2A"
			(at 292.48 213 0)
			(layer "F.Fab")
			(hide yes)
			(effects
				(font
					(size 1 1)
					(thickness 0.15)
				)
			)
		)
		(property "Manufacturer" "KYOCERA AVX"
			(at 292.48 213 0)
			(layer "F.Fab")
			(hide yes)
			(effects
				(font
					(size 1 1)
					(thickness 0.15)
				)
			)
		)
		(property "Val" "1u"
			(at 292.48 213 0)
			(layer "F.Fab")
			(hide yes)
			(effects
				(font
					(size 1 1)
					(thickness 0.15)
				)
			)
		)
		(property "Voltage" ""
			(at 292.48 213 0)
			(layer "F.Fab")
			(hide yes)
			(effects
				(font
					(size 1 1)
					(thickness 0.15)
				)
			)
		)
		(sheetname "/Power Supply/")
		(sheetfile "supply.kicad_sch")
		(attr smd)
		(fp_line
			(start -0.15 0.4)
			(end 0.15 0.4)
			(stroke
				(width 0.15)
				(type solid)
			)
			(layer "F.SilkS")
		)
		(fp_line
			(start -0.15 -0.4)
			(end 0.15 -0.4)
			(stroke
				(width 0.15)
				(type solid)
			)
			(layer "F.SilkS")
		)
		(fp_rect
			(start -1.25 -0.65)
			(end 1.25 0.65)
			(stroke
				(width 0.05)
				(type solid)
			)
			(fill no)
			(layer "F.CrtYd")
		)
		(fp_rect
			(start -0.8 -0.4)
			(end 0.8 0.4)
			(stroke
				(width 0.15)
				(type solid)
			)
			(fill no)
			(layer "F.Fab")
		)
		(fp_text user "License: Apache-2.0"
			(at -1.682 5.895 180)
			(layer "F.Fab")
			(effects
				(font
					(size 0.7 0.7)
					(thickness 0.15)
				)
				(justify left bottom)
			)
		)
		(fp_text user "${REFERENCE}"
			(at -1.682 3.895 180)
			(layer "F.Fab")
			(effects
				(font
					(size 0.7 0.7)
					(thickness 0.15)
				)
				(justify left bottom)
			)
		)
		(fp_text user "Author: Antmicro"
			(at -1.682 4.894 180)
			(layer "F.Fab")
			(effects
				(font
					(size 0.7 0.7)
					(thickness 0.15)
				)
				(justify left bottom)
			)
		)
		(pad "1" smd roundrect
			(at -0.7 0 180)
			(size 0.8 1)
			(layers "F.Cu" "F.Mask" "F.Paste")
			(roundrect_rratio 0.2)
			(net 2 "+3V3")
			(pintype "passive")
		)
		(pad "2" smd roundrect
			(at 0.7 0 180)
			(size 0.8 1)
			(layers "F.Cu" "F.Mask" "F.Paste")
			(roundrect_rratio 0.2)
			(net 1 "GND")
			(pintype "passive")
		)
	)
	(footprint "antmicro-footprints:TSOT23-6"
		(layer "F.Cu")
		(at 146.58 59.24 90)
		(property "Reference" "U6"
			(at 0.56 2.51 90)
			(layer "F.SilkS")
			(effects
				(font
					(size 0.65 0.65)
					(thickness 0.15)
				)
				(justify left bottom)
			)
		)
		(property "Value" "AP62301WU-7"
			(at -0.005 2.6 90)
			(layer "F.Fab")
			(hide yes)
			(effects
				(font
					(size 0.7 0.7)
					(thickness 0.15)
				)
				(justify left bottom)
			)
		)
		(property "Datasheet" "https://www.diodes.com/assets/Datasheets/AP62300_AP62301_AP62300T.pdf"
			(at 0 0 90)
			(layer "F.Fab")
			(hide yes)
			(effects
				(font
					(size 1.27 1.27)
					(thickness 0.15)
				)
			)
		)
		(property "Description" "DC-DC Switching Synchronous Buck Regulator, Adjustable, 4.2V-18Vin, 0.8V-7V/3A out, TSOT-26-6"
			(at 0 0 90)
			(layer "F.Fab")
			(hide yes)
			(effects
				(font
					(size 1.27 1.27)
					(thickness 0.15)
				)
			)
		)
		(property "Author" "Antmicro"
			(at 0 0 90)
			(layer "F.Fab")
			(hide yes)
			(effects
				(font
					(size 1 1)
					(thickness 0.15)
				)
			)
		)
		(property "License" "Apache-2.0"
			(at 0 0 90)
			(layer "F.Fab")
			(hide yes)
			(effects
				(font
					(size 1 1)
					(thickness 0.15)
				)
			)
		)
		(property "MPN" "AP62301WU-7"
			(at 0 0 90)
			(layer "F.Fab")
			(hide yes)
			(effects
				(font
					(size 1 1)
					(thickness 0.15)
				)
			)
		)
		(property "Manufacturer" "Diodes Incorporated"
			(at 0 0 90)
			(layer "F.Fab")
			(hide yes)
			(effects
				(font
					(size 1 1)
					(thickness 0.15)
				)
			)
		)
		(sheetname "/Power Supply/")
		(sheetfile "supply.kicad_sch")
		(attr smd)
		(fp_line
			(start -1 -1.5)
			(end -1 -1.375)
			(stroke
				(width 0.15)
				(type solid)
			)
			(layer "F.SilkS")
		)
		(fp_line
			(start 1 -1.497)
			(end -1 -1.5)
			(stroke
				(width 0.15)
				(type solid)
			)
			(layer "F.SilkS")
		)
		(fp_line
			(start 1 -1.497)
			(end 1 -1.375)
			(stroke
				(width 0.15)
				(type solid)
			)
			(layer "F.SilkS")
		)
		(fp_line
			(start 1 1.55)
			(end 1 1.4)
			(stroke
				(width 0.15)
				(type solid)
			)
			(layer "F.SilkS")
		)
		(fp_line
			(start 1 1.55)
			(end -1 1.55)
			(stroke
				(width 0.15)
				(type solid)
			)
			(layer "F.SilkS")
		)
		(fp_line
			(start -1 1.55)
			(end -1 1.4)
			(stroke
				(width 0.15)
				(type solid)
			)
			(layer "F.SilkS")
		)
		(fp_circle
			(center -1.44 -1.5)
			(end -1.39 -1.5)
			(stroke
				(width 0.15)
				(type solid)
			)
			(fill yes)
			(layer "F.SilkS")
		)
		(fp_rect
			(start 1.93 -1.7)
			(end -1.93 1.7)
			(stroke
				(width 0.05)
				(type solid)
			)
			(fill no)
			(layer "F.CrtYd")
		)
		(fp_line
			(start -0.45 -1.521)
			(end -0.876 -1.096)
			(stroke
				(width 0.15)
				(type solid)
			)
			(layer "F.Fab")
		)
		(fp_rect
			(start 0.875 1.528)
			(end -0.875 -1.525)
			(stroke
				(width 0.15)
				(type solid)
			)
			(fill no)
			(layer "F.Fab")
		)
		(fp_text user "Author: Antmicro"
			(at -1.93 5 90)
			(layer "F.Fab")
			(effects
				(font
					(size 0.7 0.7)
					(thickness 0.15)
				)
				(justify left bottom)
			)
		)
		(fp_text user "License: Apache-2.0"
			(at -1.93 6.199 90)
			(layer "F.Fab")
			(effects
				(font
					(size 0.7 0.7)
					(thickness 0.15)
				)
				(justify left bottom)
			)
		)
		(fp_text user "${REFERENCE}"
			(at -1.93 3.8 90)
			(layer "F.Fab")
			(effects
				(font
					(size 0.7 0.7)
					(thickness 0.15)
				)
				(justify left bottom)
			)
		)
		(pad "1" smd rect
			(at -1.301 -0.947)
			(size 0.7 1.2)
			(layers "F.Cu" "F.Mask" "F.Paste")
			(net 1 "GND")
			(pinfunction "GND")
			(pintype "power_in")
		)
		(pad "2" smd rect
			(at -1.301 0.004)
			(size 0.7 1.2)
			(layers "F.Cu" "F.Mask" "F.Paste")
			(net 277 "/Power Supply/1V5_SW")
			(pinfunction "SW")
			(pintype "power_out")
		)
		(pad "3" smd rect
			(at -1.301 0.954)
			(size 0.7 1.2)
			(layers "F.Cu" "F.Mask" "F.Paste")
			(net 327 "/Power Supply/5V_1V5_IN")
			(pinfunction "VIN")
			(pintype "power_in")
		)
		(pad "4" smd rect
			(at 1.299 0.954)
			(size 0.7 1.2)
			(layers "F.Cu" "F.Mask" "F.Paste")
			(net 263 "Net-(U6-FB)")
			(pinfunction "FB")
			(pintype "input")
		)
		(pad "5" smd rect
			(at 1.299 0.004)
			(size 0.7 1.2)
			(layers "F.Cu" "F.Mask" "F.Paste")
			(net 374 "Net-(U6-EN)")
			(pinfunction "EN")
			(pintype "input")
		)
		(pad "6" smd rect
			(at 1.299 -0.947)
			(size 0.7 1.2)
			(layers "F.Cu" "F.Mask" "F.Paste")
			(net 65 "Net-(U6-BST)")
			(pinfunction "BST")
			(pintype "output")
		)
	)
)
